(kicad_pcb
	(version 20241229)
	(generator "pcbnew")
	(generator_version "9.0")
	(general
		(thickness 1.294)
		(legacy_teardrops no)
	)
	(paper "A3")
	(title_block
		(title "Kintex 410T devboard")
		(date "2024-04-03")
		(rev "1.1.2")
		(comment 9 "footprints 567-572 of 975")
	)
	(layers
		(0 "F.Cu" mixed)
		(4 "In1.Cu" power)
		(6 "In2.Cu" power)
		(8 "In3.Cu" mixed)
		(10 "In4.Cu" power)
		(12 "In5.Cu" mixed)
		(14 "In6.Cu" power)
		(16 "In7.Cu" mixed)
		(18 "In8.Cu" power)
		(2 "B.Cu" mixed)
		(9 "F.Adhes" user "F.Adhesive")
		(11 "B.Adhes" user "B.Adhesive")
		(13 "F.Paste" user)
		(15 "B.Paste" user)
		(5 "F.SilkS" user "F.Silkscreen")
		(7 "B.SilkS" user "B.Silkscreen")
		(1 "F.Mask" user)
		(3 "B.Mask" user)
		(17 "Dwgs.User" user "User.Drawings")
		(19 "Cmts.User" user "User.Comments")
		(21 "Eco1.User" user "User.Eco1")
		(23 "Eco2.User" user "User.Eco2")
		(25 "Edge.Cuts" user)
		(27 "Margin" user)
		(31 "F.CrtYd" user "F.Courtyard")
		(29 "B.CrtYd" user "B.Courtyard")
		(35 "F.Fab" user)
		(33 "B.Fab" user)
	)
	(footprint "antmicro-footprints:R_Array_4x0201_Panasonic_EXB18V"
		(layer "B.Cu")
		(at 249.901 127.9)
		(property "Reference" "R21"
			(at 1.049 -0.725 0)
			(layer "B.SilkS")
			(effects
				(font
					(size 0.7 0.7)
					(thickness 0.15)
				)
				(justify left bottom mirror)
			)
		)
		(property "Value" "R_4x33R_0201_array"
			(at -1.1 -1.8 0)
			(layer "B.Fab")
			(effects
				(font
					(size 0.7 0.7)
					(thickness 0.15)
				)
				(justify right bottom mirror)
			)
		)
		(property "Description" "Fixed Network Resistor, 33 ohm, Isolated, 4 Resistors, 0502 [1406 Metric], Flat, ± 5%"
			(at 0 0 0)
			(layer "F.Fab")
			(hide yes)
			(effects
				(font
					(size 1.27 1.27)
					(thickness 0.15)
				)
			)
		)
		(property "Author" "Antmicro"
			(at 0 0 0)
			(layer "B.Fab")
			(hide yes)
			(effects
				(font
					(size 1 1)
					(thickness 0.15)
				)
				(justify mirror)
			)
		)
		(property "License" "Apache-2.0"
			(at 0 0 0)
			(layer "B.Fab")
			(hide yes)
			(effects
				(font
					(size 1 1)
					(thickness 0.15)
				)
				(justify mirror)
			)
		)
		(property "MPN" "EXB-18V330JX"
			(at 0 0 0)
			(layer "B.Fab")
			(hide yes)
			(effects
				(font
					(size 1 1)
					(thickness 0.15)
				)
				(justify mirror)
			)
		)
		(property "Manufacturer" "Panasonic"
			(at 0 0 0)
			(layer "B.Fab")
			(hide yes)
			(effects
				(font
					(size 1 1)
					(thickness 0.15)
				)
				(justify mirror)
			)
		)
		(property "Val" "R_4x33R_0201"
			(at 0 0 0)
			(layer "B.Fab")
			(hide yes)
			(effects
				(font
					(size 1 1)
					(thickness 0.15)
				)
				(justify mirror)
			)
		)
		(sheetname "Supervisior MCU")
		(sheetfile "supervisor-mcu.kicad_sch")
		(attr smd)
		(fp_line
			(start -0.8 0.45)
			(end -0.8 -0.45)
			(stroke
				(width 0.12)
				(type solid)
			)
			(layer "B.SilkS")
		)
		(fp_line
			(start 0.8 0.45)
			(end 0.8 -0.45)
			(stroke
				(width 0.12)
				(type solid)
			)
			(layer "B.SilkS")
		)
		(fp_rect
			(start -0.898 0.66)
			(end 0.898 -0.65)
			(stroke
				(width 0.05)
				(type solid)
			)
			(fill no)
			(layer "B.CrtYd")
		)
		(pad "1" smd roundrect
			(at -0.6 -0.298)
			(size 0.2 0.4)
			(layers "B.Cu" "B.Mask" "B.Paste")
			(roundrect_rratio 0.25)
			(net 1353 "/SUP_MCU.A1")
			(pinfunction "R1.1")
			(pintype "passive")
		)
		(pad "2" smd roundrect
			(at -0.202 -0.298)
			(size 0.2 0.4)
			(layers "B.Cu" "B.Mask" "B.Paste")
			(roundrect_rratio 0.25)
			(net 1354 "/SUP_MCU.A7")
			(pinfunction "R2.1")
			(pintype "passive")
		)
		(pad "3" smd roundrect
			(at 0.2 -0.298)
			(size 0.2 0.4)
			(layers "B.Cu" "B.Mask" "B.Paste")
			(roundrect_rratio 0.25)
			(net 1355 "/SUP_MCU.A16")
			(pinfunction "R3.1")
			(pintype "passive")
		)
		(pad "4" smd roundrect
			(at 0.598 -0.298)
			(size 0.2 0.4)
			(layers "B.Cu" "B.Mask" "B.Paste")
			(roundrect_rratio 0.25)
			(net 1356 "/SUP_MCU.A18")
			(pinfunction "R4.1")
			(pintype "passive")
		)
		(pad "5" smd roundrect
			(at 0.598 0.3)
			(size 0.2 0.4)
			(layers "B.Cu" "B.Mask" "B.Paste")
			(roundrect_rratio 0.25)
			(net 1079 "/Supervisior MCU/USB_A18")
			(pinfunction "R4.2")
			(pintype "passive")
		)
		(pad "6" smd roundrect
			(at 0.2 0.3)
			(size 0.2 0.4)
			(layers "B.Cu" "B.Mask" "B.Paste")
			(roundrect_rratio 0.25)
			(net 1077 "/Supervisior MCU/USB_A16")
			(pinfunction "R3.2")
			(pintype "passive")
		)
		(pad "7" smd roundrect
			(at -0.202 0.3)
			(size 0.2 0.4)
			(layers "B.Cu" "B.Mask" "B.Paste")
			(roundrect_rratio 0.25)
			(net 1068 "/Supervisior MCU/USB_A7")
			(pinfunction "R2.2")
			(pintype "passive")
		)
		(pad "8" smd roundrect
			(at -0.6 0.3)
			(size 0.2 0.4)
			(layers "B.Cu" "B.Mask" "B.Paste")
			(roundrect_rratio 0.25)
			(net 1062 "/Supervisior MCU/USB_A1")
			(pinfunction "R1.2")
			(pintype "passive")
		)
	)
	(footprint "antmicro-footprints:C_0402_1005Metric"
		(layer "B.Cu")
		(at 171.999999 147.999999 90)
		(descr "Capacitor SMD 0402")
		(tags "capacitor SMD 0402")
		(property "Reference" "C182"
			(at -0.725001 0.400001 270)
			(layer "B.SilkS")
			(effects
				(font
					(size 0.7 0.7)
					(thickness 0.15)
				)
				(justify left bottom mirror)
			)
		)
		(property "Value" "C_100n_0402"
			(at 0 -1.169 270)
			(layer "B.Fab")
			(effects
				(font
					(size 0.7 0.7)
					(thickness 0.15)
				)
				(justify left bottom mirror)
			)
		)
		(property "Description" "SMD Multilayer Ceramic Capacitor, 0.1 µF, 50 V, 0402 [1005 Metric], ± 10%, X5R, GRM Series"
			(at 0 0 90)
			(layer "F.Fab")
			(hide yes)
			(effects
				(font
					(size 1.27 1.27)
					(thickness 0.15)
				)
			)
		)
		(property "Author" "Antmicro"
			(at 319.999998 -24 0)
			(layer "B.Fab")
			(hide yes)
			(effects
				(font
					(size 1 1)
					(thickness 0.15)
				)
				(justify mirror)
			)
		)
		(property "Dielectric" "X5R"
			(at 319.999998 -24 0)
			(layer "B.Fab")
			(hide yes)
			(effects
				(font
					(size 1 1)
					(thickness 0.15)
				)
				(justify mirror)
			)
		)
		(property "License" "Apache-2.0"
			(at 319.999998 -24 0)
			(layer "B.Fab")
			(hide yes)
			(effects
				(font
					(size 1 1)
					(thickness 0.15)
				)
				(justify mirror)
			)
		)
		(property "MPN" "GRM155R61H104KE14D"
			(at 319.999998 -24 0)
			(layer "B.Fab")
			(hide yes)
			(effects
				(font
					(size 1 1)
					(thickness 0.15)
				)
				(justify mirror)
			)
		)
		(property "Manufacturer" "Murata"
			(at 319.999998 -24 0)
			(layer "B.Fab")
			(hide yes)
			(effects
				(font
					(size 1 1)
					(thickness 0.15)
				)
				(justify mirror)
			)
		)
		(property "Val" "100n"
			(at 319.999998 -24 0)
			(layer "B.Fab")
			(hide yes)
			(effects
				(font
					(size 1 1)
					(thickness 0.15)
				)
				(justify mirror)
			)
		)
		(property "Voltage" "50V"
			(at 319.999998 -24 0)
			(layer "B.Fab")
			(hide yes)
			(effects
				(font
					(size 1 1)
					(thickness 0.15)
				)
				(justify mirror)
			)
		)
		(sheetname "DRAM + SRAM")
		(sheetfile "ram.kicad_sch")
		(attr smd)
		(fp_rect
			(start -0.925 0.47)
			(end 0.925 -0.47)
			(stroke
				(width 0.05)
				(type default)
			)
			(fill no)
			(layer "B.CrtYd")
		)
		(fp_line
			(start 0.504 -0.248)
			(end -0.494 -0.248)
			(stroke
				(width 0.15)
				(type solid)
			)
			(layer "B.Fab")
		)
		(fp_line
			(start -0.494 -0.248)
			(end -0.494 0.25)
			(stroke
				(width 0.15)
				(type solid)
			)
			(layer "B.Fab")
		)
		(fp_line
			(start 0.504 0.25)
			(end 0.504 -0.248)
			(stroke
				(width 0.15)
				(type solid)
			)
			(layer "B.Fab")
		)
		(fp_line
			(start -0.494 0.25)
			(end 0.504 0.25)
			(stroke
				(width 0.15)
				(type solid)
			)
			(layer "B.Fab")
		)
		(pad "1" smd roundrect
			(at -0.48 0 90)
			(size 0.59 0.64)
			(layers "B.Cu" "B.Mask" "B.Paste")
			(roundrect_rratio 0.25)
			(net 1 "GND")
			(pintype "passive")
		)
		(pad "2" smd roundrect
			(at 0.48 0 90)
			(size 0.59 0.64)
			(layers "B.Cu" "B.Mask" "B.Paste")
			(roundrect_rratio 0.25)
			(net 25 "+1V35")
			(pintype "passive")
		)
	)
	(footprint "antmicro-footprints:R_0402_1005Metric"
		(layer "B.Cu")
		(at 256.901 170.34762)
		(descr "Resistor SMD 0402")
		(tags "resistor SMD 0402")
		(property "Reference" "R38"
			(at 2.549 -1.64762 225)
			(layer "B.SilkS")
			(effects
				(font
					(size 0.7 0.7)
					(thickness 0.15)
				)
				(justify left bottom mirror)
			)
		)
		(property "Value" "R_100k_0402"
			(at 0 -1.4 180)
			(layer "B.Fab")
			(effects
				(font
					(size 0.7 0.7)
					(thickness 0.15)
				)
				(justify left bottom mirror)
			)
		)
		(property "Description" "SMD Chip Resistor, 100 kohm, ± 1%, 62.5 mW, 0402 [1005 Metric], Thick Film, General Purpose"
			(at 0 0 0)
			(layer "F.Fab")
			(hide yes)
			(effects
				(font
					(size 1.27 1.27)
					(thickness 0.15)
				)
			)
		)
		(property "Author" "Antmicro"
			(at 0 0 0)
			(layer "B.Fab")
			(hide yes)
			(effects
				(font
					(size 1 1)
					(thickness 0.15)
				)
				(justify mirror)
			)
		)
		(property "License" "Apache-2.0"
			(at 0 0 0)
			(layer "B.Fab")
			(hide yes)
			(effects
				(font
					(size 1 1)
					(thickness 0.15)
				)
				(justify mirror)
			)
		)
		(property "MPN" "CR0402-FX-1003GLF"
			(at 0 0 0)
			(layer "B.Fab")
			(hide yes)
			(effects
				(font
					(size 1 1)
					(thickness 0.15)
				)
				(justify mirror)
			)
		)
		(property "Manufacturer" "Bourns"
			(at 0 0 0)
			(layer "B.Fab")
			(hide yes)
			(effects
				(font
					(size 1 1)
					(thickness 0.15)
				)
				(justify mirror)
			)
		)
		(property "Tolerance" "1%"
			(at 0 0 0)
			(layer "B.Fab")
			(hide yes)
			(effects
				(font
					(size 1 1)
					(thickness 0.15)
				)
				(justify mirror)
			)
		)
		(property "Val" "100k"
			(at 0 0 0)
			(layer "B.Fab")
			(hide yes)
			(effects
				(font
					(size 1 1)
					(thickness 0.15)
				)
				(justify mirror)
			)
		)
		(sheetname "Power supply")
		(sheetfile "power-supply.kicad_sch")
		(attr smd)
		(fp_rect
			(start -0.925 0.47)
			(end 0.925 -0.47)
			(stroke
				(width 0.05)
				(type default)
			)
			(fill no)
			(layer "B.CrtYd")
		)
		(fp_rect
			(start -0.5 0.25)
			(end 0.5 -0.25)
			(stroke
				(width 0.15)
				(type solid)
			)
			(fill no)
			(layer "B.Fab")
		)
		(pad "1" smd roundrect
			(at -0.48 0)
			(size 0.59 0.64)
			(layers "B.Cu" "B.Mask" "B.Paste")
			(roundrect_rratio 0.25)
			(net 889 "/Power supply/PG")
			(pintype "passive")
		)
		(pad "2" smd roundrect
			(at 0.48 0)
			(size 0.59 0.64)
			(layers "B.Cu" "B.Mask" "B.Paste")
			(roundrect_rratio 0.25)
			(net 698 "/Power supply/VDD")
			(pintype "passive")
		)
	)
	(footprint "antmicro-footprints:C_0402_1005Metric"
		(layer "B.Cu")
		(at 247.6 78.7)
		(descr "Capacitor SMD 0402")
		(tags "capacitor SMD 0402")
		(property "Reference" "C215"
			(at -1.25 -0.55 0)
			(layer "B.SilkS")
			(effects
				(font
					(size 0.7 0.7)
					(thickness 0.15)
				)
				(justify right bottom mirror)
			)
		)
		(property "Value" "C_1u_0402"
			(at 0 -1.4 0)
			(layer "B.Fab")
			(effects
				(font
					(size 0.7 0.7)
					(thickness 0.15)
				)
				(justify right bottom mirror)
			)
		)
		(property "Description" "SMD Multilayer Ceramic Capacitor, 1 µF, 10 V, 0402 [1005 Metric], ± 10%, X6S, C"
			(at 0 0 0)
			(layer "F.Fab")
			(hide yes)
			(effects
				(font
					(size 1.27 1.27)
					(thickness 0.15)
				)
			)
		)
		(property "Author" "Antmicro"
			(at 0 0 0)
			(layer "B.Fab")
			(hide yes)
			(effects
				(font
					(size 1 1)
					(thickness 0.15)
				)
				(justify mirror)
			)
		)
		(property "Dielectric" ""
			(at 0 0 0)
			(layer "B.Fab")
			(hide yes)
			(effects
				(font
					(size 1 1)
					(thickness 0.15)
				)
				(justify mirror)
			)
		)
		(property "License" "Apache-2.0"
			(at 0 0 0)
			(layer "B.Fab")
			(hide yes)
			(effects
				(font
					(size 1 1)
					(thickness 0.15)
				)
				(justify mirror)
			)
		)
		(property "MPN" "C1005X6S1A105K050BC"
			(at 0 0 0)
			(layer "B.Fab")
			(hide yes)
			(effects
				(font
					(size 1 1)
					(thickness 0.15)
				)
				(justify mirror)
			)
		)
		(property "Manufacturer" "TDK"
			(at 0 0 0)
			(layer "B.Fab")
			(hide yes)
			(effects
				(font
					(size 1 1)
					(thickness 0.15)
				)
				(justify mirror)
			)
		)
		(property "Val" "1u"
			(at 0 0 0)
			(layer "B.Fab")
			(hide yes)
			(effects
				(font
					(size 1 1)
					(thickness 0.15)
				)
				(justify mirror)
			)
		)
		(property "Voltage" ""
			(at 0 0 0)
			(layer "B.Fab")
			(hide yes)
			(effects
				(font
					(size 1 1)
					(thickness 0.15)
				)
				(justify mirror)
			)
		)
		(sheetname "User GPIO + LED + button + DIP switch")
		(sheetfile "user-gpio.kicad_sch")
		(attr smd)
		(fp_rect
			(start -0.925 0.47)
			(end 0.925 -0.47)
			(stroke
				(width 0.05)
				(type default)
			)
			(fill no)
			(layer "B.CrtYd")
		)
		(fp_line
			(start -0.494 -0.248)
			(end -0.494 0.25)
			(stroke
				(width 0.15)
				(type solid)
			)
			(layer "B.Fab")
		)
		(fp_line
			(start -0.494 0.25)
			(end 0.504 0.25)
			(stroke
				(width 0.15)
				(type solid)
			)
			(layer "B.Fab")
		)
		(fp_line
			(start 0.504 -0.248)
			(end -0.494 -0.248)
			(stroke
				(width 0.15)
				(type solid)
			)
			(layer "B.Fab")
		)
		(fp_line
			(start 0.504 0.25)
			(end 0.504 -0.248)
			(stroke
				(width 0.15)
				(type solid)
			)
			(layer "B.Fab")
		)
		(pad "1" smd roundrect
			(at -0.48 0)
			(size 0.59 0.64)
			(layers "B.Cu" "B.Mask" "B.Paste")
			(roundrect_rratio 0.25)
			(net 1 "GND")
			(pintype "passive")
		)
		(pad "2" smd roundrect
			(at 0.48 0)
			(size 0.59 0.64)
			(layers "B.Cu" "B.Mask" "B.Paste")
			(roundrect_rratio 0.25)
			(net 24 "+3V3")
			(pintype "passive")
		)
	)
	(footprint "antmicro-footprints:R_0402_1005Metric"
		(layer "B.Cu")
		(at 195.691252 92.85 180)
		(descr "Resistor SMD 0402")
		(tags "resistor SMD 0402")
		(property "Reference" "R200"
			(at 0.716252 -0.425 0)
			(layer "B.SilkS")
			(effects
				(font
					(size 0.7 0.7)
					(thickness 0.15)
				)
				(justify left bottom mirror)
			)
		)
		(property "Value" "R_10k_0402"
			(at 0 -1.4 0)
			(layer "B.Fab")
			(effects
				(font
					(size 0.7 0.7)
					(thickness 0.15)
				)
				(justify left bottom mirror)
			)
		)
		(property "Description" "SMD Chip Resistor, 10 kohm, ± 1%, 62.5 mW, 0402 [1005 Metric], Thick Film, General Purpose"
			(at 0 0 180)
			(layer "F.Fab")
			(hide yes)
			(effects
				(font
					(size 1.27 1.27)
					(thickness 0.15)
				)
			)
		)
		(property "Author" "Antmicro"
			(at 391.382504 185.7 0)
			(layer "B.Fab")
			(hide yes)
			(effects
				(font
					(size 1 1)
					(thickness 0.15)
				)
				(justify mirror)
			)
		)
		(property "License" "Apache-2.0"
			(at 391.382504 185.7 0)
			(layer "B.Fab")
			(hide yes)
			(effects
				(font
					(size 1 1)
					(thickness 0.15)
				)
				(justify mirror)
			)
		)
		(property "MPN" "CR0402-FX-1002GLF"
			(at 391.382504 185.7 0)
			(layer "B.Fab")
			(hide yes)
			(effects
				(font
					(size 1 1)
					(thickness 0.15)
				)
				(justify mirror)
			)
		)
		(property "Manufacturer" "Bourns"
			(at 391.382504 185.7 0)
			(layer "B.Fab")
			(hide yes)
			(effects
				(font
					(size 1 1)
					(thickness 0.15)
				)
				(justify mirror)
			)
		)
		(property "Tolerance" "1%"
			(at 391.382504 185.7 0)
			(layer "B.Fab")
			(hide yes)
			(effects
				(font
					(size 1 1)
					(thickness 0.15)
				)
				(justify mirror)
			)
		)
		(property "Val" "10k"
			(at 391.382504 185.7 0)
			(layer "B.Fab")
			(hide yes)
			(effects
				(font
					(size 1 1)
					(thickness 0.15)
				)
				(justify mirror)
			)
		)
		(sheetname "HDMI + Ethernet")
		(sheetfile "hdmi-ethernet.kicad_sch")
		(attr smd)
		(fp_rect
			(start -0.925 0.47)
			(end 0.925 -0.47)
			(stroke
				(width 0.05)
				(type default)
			)
			(fill no)
			(layer "B.CrtYd")
		)
		(fp_rect
			(start -0.5 0.25)
			(end 0.5 -0.25)
			(stroke
				(width 0.15)
				(type solid)
			)
			(fill no)
			(layer "B.Fab")
		)
		(pad "1" smd roundrect
			(at -0.48 0 180)
			(size 0.59 0.64)
			(layers "B.Cu" "B.Mask" "B.Paste")
			(roundrect_rratio 0.25)
			(net 504 "/FPGA Bank 16 & 17/GBE_RGMII.RXD2")
			(pintype "passive")
		)
		(pad "2" smd roundrect
			(at 0.48 0 180)
			(size 0.59 0.64)
			(layers "B.Cu" "B.Mask" "B.Paste")
			(roundrect_rratio 0.25)
			(net 24 "+3V3")
			(pintype "passive")
		)
	)
	(footprint "antmicro-footprints:NetTie-2_SMD_Pad0.127mm"
		(layer "B.Cu")
		(at 193.59 145.48 180)
		(descr "Net tie, 2 pin, 0.127mm  SMD pads")
		(tags "net tie")
		(property "Reference" "NT35"
			(at -0.128 1.345 0)
			(layer "B.SilkS")
			(hide yes)
			(effects
				(font
					(size 0.7 0.7)
					(thickness 0.15)
				)
				(justify left bottom mirror)
			)
		)
		(property "Value" "Net-Tie_2"
			(at 0 -1.199 0)
			(layer "B.Fab")
			(effects
				(font
					(size 0.7 0.7)
					(thickness 0.15)
				)
				(justify left bottom mirror)
			)
		)
		(property "Description" "Net tie, 2 pins"
			(at 0 0 180)
			(layer "F.Fab")
			(hide yes)
			(effects
				(font
					(size 1.27 1.27)
					(thickness 0.15)
				)
			)
		)
		(property "Author" "Antmicro"
			(at 387.18 290.96 0)
			(layer "B.Fab")
			(hide yes)
			(effects
				(font
					(size 1 1)
					(thickness 0.15)
				)
				(justify mirror)
			)
		)
		(property "License" "Apache-2.0"
			(at 387.18 290.96 0)
			(layer "B.Fab")
			(hide yes)
			(effects
				(font
					(size 1 1)
					(thickness 0.15)
				)
				(justify mirror)
			)
		)
		(property "MPN" ""
			(at 387.18 290.96 0)
			(layer "B.Fab")
			(hide yes)
			(effects
				(font
					(size 1 1)
					(thickness 0.15)
				)
				(justify mirror)
			)
		)
		(property "Manufacturer" ""
			(at 387.18 290.96 0)
			(layer "B.Fab")
			(hide yes)
			(effects
				(font
					(size 1 1)
					(thickness 0.15)
				)
				(justify mirror)
			)
		)
		(sheetname "DC-DC Converters")
		(sheetfile "dc-dc.kicad_sch")
		(attr exclude_from_pos_files)
		(net_tie_pad_groups "1, 2")
		(fp_poly
			(pts
				(xy -0.0635 0.0635) (xy 0.0625 0.0635) (xy 0.0625 -0.0635) (xy -0.0635 -0.0635)
			)
			(stroke
				(width 0)
				(type solid)
			)
			(fill yes)
			(layer "B.Cu")
		)
		(pad "1" smd roundrect
			(at -0.127 0)
			(size 0.127 0.127)
			(layers "B.Cu")
			(roundrect_rratio 0.5)
			(chamfer_ratio 0)
			(chamfer top_left bottom_left)
			(net 1 "GND")
			(pinfunction "1")
			(pintype "passive")
		)
		(pad "2" smd roundrect
			(at 0.126 0 180)
			(size 0.127 0.127)
			(layers "B.Cu")
			(roundrect_rratio 0.5)
			(chamfer_ratio 0)
			(chamfer top_left bottom_left)
			(net 1223 "/DC-DC Converters/SENSE_1V8_N")
			(pinfunction "2")
			(pintype "passive")
		)
	)
)
